(kicad_pcb
	(version 20241229)
	(generator "pcbnew")
	(generator_version "9.0")
	(general
		(thickness 1.61)
		(legacy_teardrops no)
	)
	(paper "A3")
	(title_block
		(title "SO-DIMM DDR5 Tester")
		(date "2025-11-26")
		(rev "1.3.0")
		(comment 9 "footprints 46-53 of 627")
	)
	(layers
		(0 "F.Cu" signal)
		(4 "In1.Cu" power)
		(6 "In2.Cu" mixed)
		(8 "In3.Cu" power)
		(10 "In4.Cu" mixed)
		(12 "In5.Cu" power)
		(14 "In6.Cu" mixed)
		(16 "In7.Cu" power)
		(18 "In8.Cu" power)
		(20 "In9.Cu" mixed)
		(22 "In10.Cu" power)
		(2 "B.Cu" signal)
		(9 "F.Adhes" user "F.Adhesive")
		(11 "B.Adhes" user "B.Adhesive")
		(13 "F.Paste" user)
		(15 "B.Paste" user)
		(5 "F.SilkS" user "F.Silkscreen")
		(7 "B.SilkS" user "B.Silkscreen")
		(1 "F.Mask" user)
		(3 "B.Mask" user)
		(17 "Dwgs.User" user "User.Drawings")
		(19 "Cmts.User" user "User.Comments")
		(21 "Eco1.User" user "User.Eco1")
		(23 "Eco2.User" user "User.Eco2")
		(25 "Edge.Cuts" user)
		(27 "Margin" user)
		(31 "F.CrtYd" user "F.Courtyard")
		(29 "B.CrtYd" user "B.Courtyard")
		(35 "F.Fab" user)
		(33 "B.Fab" user)
	)
	(footprint "antmicro-footprints:R_0402_1005Metric"
		(layer "F.Cu")
		(at 84.65 191.25 180)
		(descr "Resistor SMD 0402")
		(tags "resistor SMD 0402")
		(property "Reference" "R75"
			(at -1.122484 -0.772697 180)
			(layer "F.SilkS")
			(hide yes)
			(effects
				(font
					(size 0.7 0.7)
					(thickness 0.15)
				)
				(justify left bottom)
			)
		)
		(property "Value" "R_0R_0402"
			(at -1.011843 1.772047 180)
			(layer "F.Fab")
			(effects
				(font
					(size 0.7 0.7)
					(thickness 0.15)
				)
				(justify left bottom)
			)
		)
		(property "Datasheet" "https://industrial.panasonic.com/cdbs/www-data/pdf/RDA0000/AOA0000C301.pdf"
			(at 0 0 180)
			(layer "F.Fab")
			(hide yes)
			(effects
				(font
					(size 1.27 1.27)
					(thickness 0.15)
				)
			)
		)
		(property "Author" "Antmicro"
			(at 169.3 382.5 0)
			(layer "F.Fab")
			(hide yes)
			(effects
				(font
					(size 1 1)
					(thickness 0.15)
				)
			)
		)
		(property "Current" "1A"
			(at 169.3 382.5 0)
			(layer "F.Fab")
			(hide yes)
			(effects
				(font
					(size 1 1)
					(thickness 0.15)
				)
			)
		)
		(property "License" "Apache-2.0"
			(at 169.3 382.5 0)
			(layer "F.Fab")
			(hide yes)
			(effects
				(font
					(size 1 1)
					(thickness 0.15)
				)
			)
		)
		(property "MPN" "ERJ2GE0R00X"
			(at 169.3 382.5 0)
			(layer "F.Fab")
			(hide yes)
			(effects
				(font
					(size 1 1)
					(thickness 0.15)
				)
			)
		)
		(property "Manufacturer" "Panasonic"
			(at 169.3 382.5 0)
			(layer "F.Fab")
			(hide yes)
			(effects
				(font
					(size 1 1)
					(thickness 0.15)
				)
			)
		)
		(property "Tolerance" ""
			(at 169.3 382.5 0)
			(layer "F.Fab")
			(hide yes)
			(effects
				(font
					(size 1 1)
					(thickness 0.15)
				)
			)
		)
		(property "Val" "0R"
			(at 169.3 382.5 0)
			(layer "F.Fab")
			(hide yes)
			(effects
				(font
					(size 1 1)
					(thickness 0.15)
				)
			)
		)
		(sheetname "/HDMI + SD Card/")
		(sheetfile "hdmi-sd-card.kicad_sch")
		(attr smd)
		(fp_rect
			(start -0.93 -0.47)
			(end 0.93 0.47)
			(stroke
				(width 0.05)
				(type solid)
			)
			(fill no)
			(layer "F.CrtYd")
		)
		(fp_rect
			(start -0.5 -0.25)
			(end 0.5 0.25)
			(stroke
				(width 0.15)
				(type solid)
			)
			(fill no)
			(layer "F.Fab")
		)
		(pad "1" smd roundrect
			(at -0.485 0 180)
			(size 0.59 0.64)
			(layers "F.Cu" "F.Mask" "F.Paste")
			(roundrect_rratio 0.25)
			(net 665 "/FPGA bank 16/HDMI.D0_N")
			(pintype "passive")
		)
		(pad "2" smd roundrect
			(at 0.485 0 180)
			(size 0.59 0.64)
			(layers "F.Cu" "F.Mask" "F.Paste")
			(roundrect_rratio 0.25)
			(net 311 "/HDMI + SD Card/HDMI_CONN_D0_N")
			(pintype "passive")
		)
	)
	(footprint "antmicro-footprints:R_0402_1005Metric"
		(layer "F.Cu")
		(at 84.65 192.252 180)
		(descr "Resistor SMD 0402")
		(tags "resistor SMD 0402")
		(property "Reference" "R74"
			(at -1.122484 -0.772697 180)
			(layer "F.SilkS")
			(hide yes)
			(effects
				(font
					(size 0.7 0.7)
					(thickness 0.15)
				)
				(justify left bottom)
			)
		)
		(property "Value" "R_0R_0402"
			(at -1.011843 1.772047 180)
			(layer "F.Fab")
			(effects
				(font
					(size 0.7 0.7)
					(thickness 0.15)
				)
				(justify left bottom)
			)
		)
		(property "Datasheet" "https://industrial.panasonic.com/cdbs/www-data/pdf/RDA0000/AOA0000C301.pdf"
			(at 0 0 180)
			(layer "F.Fab")
			(hide yes)
			(effects
				(font
					(size 1.27 1.27)
					(thickness 0.15)
				)
			)
		)
		(property "Author" "Antmicro"
			(at 169.3 384.504 0)
			(layer "F.Fab")
			(hide yes)
			(effects
				(font
					(size 1 1)
					(thickness 0.15)
				)
			)
		)
		(property "Current" "1A"
			(at 169.3 384.504 0)
			(layer "F.Fab")
			(hide yes)
			(effects
				(font
					(size 1 1)
					(thickness 0.15)
				)
			)
		)
		(property "License" "Apache-2.0"
			(at 169.3 384.504 0)
			(layer "F.Fab")
			(hide yes)
			(effects
				(font
					(size 1 1)
					(thickness 0.15)
				)
			)
		)
		(property "MPN" "ERJ2GE0R00X"
			(at 169.3 384.504 0)
			(layer "F.Fab")
			(hide yes)
			(effects
				(font
					(size 1 1)
					(thickness 0.15)
				)
			)
		)
		(property "Manufacturer" "Panasonic"
			(at 169.3 384.504 0)
			(layer "F.Fab")
			(hide yes)
			(effects
				(font
					(size 1 1)
					(thickness 0.15)
				)
			)
		)
		(property "Tolerance" ""
			(at 169.3 384.504 0)
			(layer "F.Fab")
			(hide yes)
			(effects
				(font
					(size 1 1)
					(thickness 0.15)
				)
			)
		)
		(property "Val" "0R"
			(at 169.3 384.504 0)
			(layer "F.Fab")
			(hide yes)
			(effects
				(font
					(size 1 1)
					(thickness 0.15)
				)
			)
		)
		(sheetname "/HDMI + SD Card/")
		(sheetfile "hdmi-sd-card.kicad_sch")
		(attr smd)
		(fp_rect
			(start -0.93 -0.47)
			(end 0.93 0.47)
			(stroke
				(width 0.05)
				(type solid)
			)
			(fill no)
			(layer "F.CrtYd")
		)
		(fp_rect
			(start -0.5 -0.25)
			(end 0.5 0.25)
			(stroke
				(width 0.15)
				(type solid)
			)
			(fill no)
			(layer "F.Fab")
		)
		(pad "1" smd roundrect
			(at -0.485 0 180)
			(size 0.59 0.64)
			(layers "F.Cu" "F.Mask" "F.Paste")
			(roundrect_rratio 0.25)
			(net 664 "/FPGA bank 16/HDMI.D0_P")
			(pintype "passive")
		)
		(pad "2" smd roundrect
			(at 0.485 0 180)
			(size 0.59 0.64)
			(layers "F.Cu" "F.Mask" "F.Paste")
			(roundrect_rratio 0.25)
			(net 296 "/HDMI + SD Card/HDMI_CONN_D0_P")
			(pintype "passive")
		)
	)
	(footprint "antmicro-footprints:R_0402_1005Metric"
		(layer "F.Cu")
		(at 86.9 192.85 180)
		(descr "Resistor SMD 0402")
		(tags "resistor SMD 0402")
		(property "Reference" "R73"
			(at -1.122484 -0.772697 180)
			(layer "F.SilkS")
			(hide yes)
			(effects
				(font
					(size 0.7 0.7)
					(thickness 0.15)
				)
				(justify left bottom)
			)
		)
		(property "Value" "R_0R_0402"
			(at -1.011843 1.772047 180)
			(layer "F.Fab")
			(effects
				(font
					(size 0.7 0.7)
					(thickness 0.15)
				)
				(justify left bottom)
			)
		)
		(property "Datasheet" "https://industrial.panasonic.com/cdbs/www-data/pdf/RDA0000/AOA0000C301.pdf"
			(at 0 0 180)
			(layer "F.Fab")
			(hide yes)
			(effects
				(font
					(size 1.27 1.27)
					(thickness 0.15)
				)
			)
		)
		(property "Author" "Antmicro"
			(at 173.8 385.7 0)
			(layer "F.Fab")
			(hide yes)
			(effects
				(font
					(size 1 1)
					(thickness 0.15)
				)
			)
		)
		(property "Current" "1A"
			(at 173.8 385.7 0)
			(layer "F.Fab")
			(hide yes)
			(effects
				(font
					(size 1 1)
					(thickness 0.15)
				)
			)
		)
		(property "License" "Apache-2.0"
			(at 173.8 385.7 0)
			(layer "F.Fab")
			(hide yes)
			(effects
				(font
					(size 1 1)
					(thickness 0.15)
				)
			)
		)
		(property "MPN" "ERJ2GE0R00X"
			(at 173.8 385.7 0)
			(layer "F.Fab")
			(hide yes)
			(effects
				(font
					(size 1 1)
					(thickness 0.15)
				)
			)
		)
		(property "Manufacturer" "Panasonic"
			(at 173.8 385.7 0)
			(layer "F.Fab")
			(hide yes)
			(effects
				(font
					(size 1 1)
					(thickness 0.15)
				)
			)
		)
		(property "Tolerance" ""
			(at 173.8 385.7 0)
			(layer "F.Fab")
			(hide yes)
			(effects
				(font
					(size 1 1)
					(thickness 0.15)
				)
			)
		)
		(property "Val" "0R"
			(at 173.8 385.7 0)
			(layer "F.Fab")
			(hide yes)
			(effects
				(font
					(size 1 1)
					(thickness 0.15)
				)
			)
		)
		(sheetname "/HDMI + SD Card/")
		(sheetfile "hdmi-sd-card.kicad_sch")
		(attr smd)
		(fp_rect
			(start -0.93 -0.47)
			(end 0.93 0.47)
			(stroke
				(width 0.05)
				(type solid)
			)
			(fill no)
			(layer "F.CrtYd")
		)
		(fp_rect
			(start -0.5 -0.25)
			(end 0.5 0.25)
			(stroke
				(width 0.15)
				(type solid)
			)
			(fill no)
			(layer "F.Fab")
		)
		(pad "1" smd roundrect
			(at -0.485 0 180)
			(size 0.59 0.64)
			(layers "F.Cu" "F.Mask" "F.Paste")
			(roundrect_rratio 0.25)
			(net 663 "/FPGA bank 16/HDMI.D1_N")
			(pintype "passive")
		)
		(pad "2" smd roundrect
			(at 0.485 0 180)
			(size 0.59 0.64)
			(layers "F.Cu" "F.Mask" "F.Paste")
			(roundrect_rratio 0.25)
			(net 295 "/HDMI + SD Card/HDMI_CONN_D1_N")
			(pintype "passive")
		)
	)
	(footprint "antmicro-footprints:R_0402_1005Metric"
		(layer "F.Cu")
		(at 86.9 193.85 180)
		(descr "Resistor SMD 0402")
		(tags "resistor SMD 0402")
		(property "Reference" "R72"
			(at -1.122484 -0.772697 180)
			(layer "F.SilkS")
			(hide yes)
			(effects
				(font
					(size 0.7 0.7)
					(thickness 0.15)
				)
				(justify left bottom)
			)
		)
		(property "Value" "R_0R_0402"
			(at -1.011843 1.772047 180)
			(layer "F.Fab")
			(effects
				(font
					(size 0.7 0.7)
					(thickness 0.15)
				)
				(justify left bottom)
			)
		)
		(property "Datasheet" "https://industrial.panasonic.com/cdbs/www-data/pdf/RDA0000/AOA0000C301.pdf"
			(at 0 0 180)
			(layer "F.Fab")
			(hide yes)
			(effects
				(font
					(size 1.27 1.27)
					(thickness 0.15)
				)
			)
		)
		(property "Author" "Antmicro"
			(at 173.8 387.7 0)
			(layer "F.Fab")
			(hide yes)
			(effects
				(font
					(size 1 1)
					(thickness 0.15)
				)
			)
		)
		(property "Current" "1A"
			(at 173.8 387.7 0)
			(layer "F.Fab")
			(hide yes)
			(effects
				(font
					(size 1 1)
					(thickness 0.15)
				)
			)
		)
		(property "License" "Apache-2.0"
			(at 173.8 387.7 0)
			(layer "F.Fab")
			(hide yes)
			(effects
				(font
					(size 1 1)
					(thickness 0.15)
				)
			)
		)
		(property "MPN" "ERJ2GE0R00X"
			(at 173.8 387.7 0)
			(layer "F.Fab")
			(hide yes)
			(effects
				(font
					(size 1 1)
					(thickness 0.15)
				)
			)
		)
		(property "Manufacturer" "Panasonic"
			(at 173.8 387.7 0)
			(layer "F.Fab")
			(hide yes)
			(effects
				(font
					(size 1 1)
					(thickness 0.15)
				)
			)
		)
		(property "Tolerance" ""
			(at 173.8 387.7 0)
			(layer "F.Fab")
			(hide yes)
			(effects
				(font
					(size 1 1)
					(thickness 0.15)
				)
			)
		)
		(property "Val" "0R"
			(at 173.8 387.7 0)
			(layer "F.Fab")
			(hide yes)
			(effects
				(font
					(size 1 1)
					(thickness 0.15)
				)
			)
		)
		(sheetname "/HDMI + SD Card/")
		(sheetfile "hdmi-sd-card.kicad_sch")
		(attr smd)
		(fp_rect
			(start -0.93 -0.47)
			(end 0.93 0.47)
			(stroke
				(width 0.05)
				(type solid)
			)
			(fill no)
			(layer "F.CrtYd")
		)
		(fp_rect
			(start -0.5 -0.25)
			(end 0.5 0.25)
			(stroke
				(width 0.15)
				(type solid)
			)
			(fill no)
			(layer "F.Fab")
		)
		(pad "1" smd roundrect
			(at -0.485 0 180)
			(size 0.59 0.64)
			(layers "F.Cu" "F.Mask" "F.Paste")
			(roundrect_rratio 0.25)
			(net 662 "/FPGA bank 16/HDMI.D1_P")
			(pintype "passive")
		)
		(pad "2" smd roundrect
			(at 0.485 0 180)
			(size 0.59 0.64)
			(layers "F.Cu" "F.Mask" "F.Paste")
			(roundrect_rratio 0.25)
			(net 294 "/HDMI + SD Card/HDMI_CONN_D1_P")
			(pintype "passive")
		)
	)
	(footprint "antmicro-footprints:R_0402_1005Metric"
		(layer "F.Cu")
		(at 84.65 194.35 180)
		(descr "Resistor SMD 0402")
		(tags "resistor SMD 0402")
		(property "Reference" "R71"
			(at -1.122484 -0.772697 180)
			(layer "F.SilkS")
			(hide yes)
			(effects
				(font
					(size 0.7 0.7)
					(thickness 0.15)
				)
				(justify left bottom)
			)
		)
		(property "Value" "R_0R_0402"
			(at -1.011843 1.772047 180)
			(layer "F.Fab")
			(effects
				(font
					(size 0.7 0.7)
					(thickness 0.15)
				)
				(justify left bottom)
			)
		)
		(property "Datasheet" "https://industrial.panasonic.com/cdbs/www-data/pdf/RDA0000/AOA0000C301.pdf"
			(at 0 0 180)
			(layer "F.Fab")
			(hide yes)
			(effects
				(font
					(size 1.27 1.27)
					(thickness 0.15)
				)
			)
		)
		(property "Author" "Antmicro"
			(at 169.3 388.7 0)
			(layer "F.Fab")
			(hide yes)
			(effects
				(font
					(size 1 1)
					(thickness 0.15)
				)
			)
		)
		(property "Current" "1A"
			(at 169.3 388.7 0)
			(layer "F.Fab")
			(hide yes)
			(effects
				(font
					(size 1 1)
					(thickness 0.15)
				)
			)
		)
		(property "License" "Apache-2.0"
			(at 169.3 388.7 0)
			(layer "F.Fab")
			(hide yes)
			(effects
				(font
					(size 1 1)
					(thickness 0.15)
				)
			)
		)
		(property "MPN" "ERJ2GE0R00X"
			(at 169.3 388.7 0)
			(layer "F.Fab")
			(hide yes)
			(effects
				(font
					(size 1 1)
					(thickness 0.15)
				)
			)
		)
		(property "Manufacturer" "Panasonic"
			(at 169.3 388.7 0)
			(layer "F.Fab")
			(hide yes)
			(effects
				(font
					(size 1 1)
					(thickness 0.15)
				)
			)
		)
		(property "Tolerance" ""
			(at 169.3 388.7 0)
			(layer "F.Fab")
			(hide yes)
			(effects
				(font
					(size 1 1)
					(thickness 0.15)
				)
			)
		)
		(property "Val" "0R"
			(at 169.3 388.7 0)
			(layer "F.Fab")
			(hide yes)
			(effects
				(font
					(size 1 1)
					(thickness 0.15)
				)
			)
		)
		(sheetname "/HDMI + SD Card/")
		(sheetfile "hdmi-sd-card.kicad_sch")
		(attr smd)
		(fp_rect
			(start -0.93 -0.47)
			(end 0.93 0.47)
			(stroke
				(width 0.05)
				(type solid)
			)
			(fill no)
			(layer "F.CrtYd")
		)
		(fp_rect
			(start -0.5 -0.25)
			(end 0.5 0.25)
			(stroke
				(width 0.15)
				(type solid)
			)
			(fill no)
			(layer "F.Fab")
		)
		(pad "1" smd roundrect
			(at -0.485 0 180)
			(size 0.59 0.64)
			(layers "F.Cu" "F.Mask" "F.Paste")
			(roundrect_rratio 0.25)
			(net 661 "/FPGA bank 16/HDMI.D2_N")
			(pintype "passive")
		)
		(pad "2" smd roundrect
			(at 0.485 0 180)
			(size 0.59 0.64)
			(layers "F.Cu" "F.Mask" "F.Paste")
			(roundrect_rratio 0.25)
			(net 293 "/HDMI + SD Card/HDMI_CONN_D2_N")
			(pintype "passive")
		)
	)
	(footprint "antmicro-footprints:R_0402_1005Metric"
		(layer "F.Cu")
		(at 84.65 195.35 180)
		(descr "Resistor SMD 0402")
		(tags "resistor SMD 0402")
		(property "Reference" "R70"
			(at -1.122484 -0.772697 180)
			(layer "F.SilkS")
			(hide yes)
			(effects
				(font
					(size 0.7 0.7)
					(thickness 0.15)
				)
				(justify left bottom)
			)
		)
		(property "Value" "R_0R_0402"
			(at -1.011843 1.772047 180)
			(layer "F.Fab")
			(effects
				(font
					(size 0.7 0.7)
					(thickness 0.15)
				)
				(justify left bottom)
			)
		)
		(property "Datasheet" "https://industrial.panasonic.com/cdbs/www-data/pdf/RDA0000/AOA0000C301.pdf"
			(at 0 0 180)
			(layer "F.Fab")
			(hide yes)
			(effects
				(font
					(size 1.27 1.27)
					(thickness 0.15)
				)
			)
		)
		(property "Author" "Antmicro"
			(at 169.3 390.7 0)
			(layer "F.Fab")
			(hide yes)
			(effects
				(font
					(size 1 1)
					(thickness 0.15)
				)
			)
		)
		(property "Current" "1A"
			(at 169.3 390.7 0)
			(layer "F.Fab")
			(hide yes)
			(effects
				(font
					(size 1 1)
					(thickness 0.15)
				)
			)
		)
		(property "License" "Apache-2.0"
			(at 169.3 390.7 0)
			(layer "F.Fab")
			(hide yes)
			(effects
				(font
					(size 1 1)
					(thickness 0.15)
				)
			)
		)
		(property "MPN" "ERJ2GE0R00X"
			(at 169.3 390.7 0)
			(layer "F.Fab")
			(hide yes)
			(effects
				(font
					(size 1 1)
					(thickness 0.15)
				)
			)
		)
		(property "Manufacturer" "Panasonic"
			(at 169.3 390.7 0)
			(layer "F.Fab")
			(hide yes)
			(effects
				(font
					(size 1 1)
					(thickness 0.15)
				)
			)
		)
		(property "Tolerance" ""
			(at 169.3 390.7 0)
			(layer "F.Fab")
			(hide yes)
			(effects
				(font
					(size 1 1)
					(thickness 0.15)
				)
			)
		)
		(property "Val" "0R"
			(at 169.3 390.7 0)
			(layer "F.Fab")
			(hide yes)
			(effects
				(font
					(size 1 1)
					(thickness 0.15)
				)
			)
		)
		(sheetname "/HDMI + SD Card/")
		(sheetfile "hdmi-sd-card.kicad_sch")
		(attr smd)
		(fp_rect
			(start -0.93 -0.47)
			(end 0.93 0.47)
			(stroke
				(width 0.05)
				(type solid)
			)
			(fill no)
			(layer "F.CrtYd")
		)
		(fp_rect
			(start -0.5 -0.25)
			(end 0.5 0.25)
			(stroke
				(width 0.15)
				(type solid)
			)
			(fill no)
			(layer "F.Fab")
		)
		(pad "1" smd roundrect
			(at -0.485 0 180)
			(size 0.59 0.64)
			(layers "F.Cu" "F.Mask" "F.Paste")
			(roundrect_rratio 0.25)
			(net 660 "/FPGA bank 16/HDMI.D2_P")
			(pintype "passive")
		)
		(pad "2" smd roundrect
			(at 0.485 0 180)
			(size 0.59 0.64)
			(layers "F.Cu" "F.Mask" "F.Paste")
			(roundrect_rratio 0.25)
			(net 292 "/HDMI + SD Card/HDMI_CONN_D2_P")
			(pintype "passive")
		)
	)
	(footprint "antmicro-footprints:TP_SMD_1mm"
		(layer "F.Cu")
		(at 84.3 188.2)
		(property "Reference" "TP5"
			(at -2.65 0.85 0)
			(layer "F.SilkS")
			(effects
				(font
					(size 0.7 0.7)
					(thickness 0.15)
				)
				(justify left bottom)
			)
		)
		(property "Value" "TP_1mm_SMD"
			(at 0 1.4 0)
			(layer "F.Fab")
			(effects
				(font
					(size 0.7 0.7)
					(thickness 0.15)
				)
				(justify left bottom)
			)
		)
		(property "Author" "Antmicro"
			(at 0 0 0)
			(layer "F.Fab")
			(hide yes)
			(effects
				(font
					(size 1 1)
					(thickness 0.15)
				)
			)
		)
		(property "License" "Apache-2.0"
			(at 0 0 0)
			(layer "F.Fab")
			(hide yes)
			(effects
				(font
					(size 1 1)
					(thickness 0.15)
				)
			)
		)
		(property "MPN" ""
			(at 0 0 0)
			(layer "F.Fab")
			(hide yes)
			(effects
				(font
					(size 1 1)
					(thickness 0.15)
				)
			)
		)
		(property "Manufacturer" ""
			(at 0 0 0)
			(layer "F.Fab")
			(hide yes)
			(effects
				(font
					(size 1 1)
					(thickness 0.15)
				)
			)
		)
		(sheetname "/HDMI + SD Card/")
		(sheetfile "hdmi-sd-card.kicad_sch")
		(attr exclude_from_pos_files)
		(pad "1" smd circle
			(at 0 0)
			(size 1 1)
			(layers "F.Cu" "F.Mask")
			(net 325 "Net-(J4-CEC)")
			(pinfunction "1")
			(pintype "passive")
		)
	)
	(footprint "antmicro-footprints:TP_SMD_1mm"
		(layer "F.Cu")
		(at 83 187.3)
		(property "Reference" "TP3"
			(at -2.65 0.65 0)
			(layer "F.SilkS")
			(effects
				(font
					(size 0.7 0.7)
					(thickness 0.15)
				)
				(justify left bottom)
			)
		)
		(property "Value" "TP_1mm_SMD"
			(at 0 1.4 0)
			(layer "F.Fab")
			(effects
				(font
					(size 0.7 0.7)
					(thickness 0.15)
				)
				(justify left bottom)
			)
		)
		(property "Author" "Antmicro"
			(at 0 0 0)
			(layer "F.Fab")
			(hide yes)
			(effects
				(font
					(size 1 1)
					(thickness 0.15)
				)
			)
		)
		(property "License" "Apache-2.0"
			(at 0 0 0)
			(layer "F.Fab")
			(hide yes)
			(effects
				(font
					(size 1 1)
					(thickness 0.15)
				)
			)
		)
		(property "MPN" ""
			(at 0 0 0)
			(layer "F.Fab")
			(hide yes)
			(effects
				(font
					(size 1 1)
					(thickness 0.15)
				)
			)
		)
		(property "Manufacturer" ""
			(at 0 0 0)
			(layer "F.Fab")
			(hide yes)
			(effects
				(font
					(size 1 1)
					(thickness 0.15)
				)
			)
		)
		(sheetname "/HDMI + SD Card/")
		(sheetfile "hdmi-sd-card.kicad_sch")
		(attr exclude_from_pos_files)
		(pad "1" smd circle
			(at 0 0)
			(size 1 1)
			(layers "F.Cu" "F.Mask")
			(net 327 "Net-(J4-SCL)")
			(pinfunction "1")
			(pintype "passive")
		)
	)
)
